(kicad_pcb
	(version 20260206)
	(generator "pcbnew")
	(generator_version "10.0")
	(general
		(thickness 1.6)
		(legacy_teardrops no)
	)
	(paper "A4")
	(title_block
		(title "04192023_DAF0TMB3IC0_F0TG_MB_C_brd_V02_OCP.brd")
		(comment 1 "Grand Teton / footprints 1549-1552 of 8354")
	)
	(layers
		(0 "F.Cu" signal "TOP")
		(4 "In1.Cu" signal "GND")
		(6 "In2.Cu" signal "IN1")
		(8 "In3.Cu" signal "GND1")
		(10 "In4.Cu" signal "IN2")
		(12 "In5.Cu" signal "GND2")
		(14 "In6.Cu" signal "IN3")
		(16 "In7.Cu" signal "GND3")
		(18 "In8.Cu" signal "VCC")
		(20 "In9.Cu" signal "VCC1")
		(22 "In10.Cu" signal "GND4")
		(24 "In11.Cu" signal "IN4")
		(26 "In12.Cu" signal "GND5")
		(28 "In13.Cu" signal "IN5")
		(30 "In14.Cu" signal "GND6")
		(32 "In15.Cu" signal "IN6")
		(34 "In16.Cu" signal "GND7")
		(2 "B.Cu" signal "BOTTOM")
		(9 "F.Adhes" user "F.Adhesive")
		(11 "B.Adhes" user "B.Adhesive")
		(13 "F.Paste" user "Package Geometry/Pastemask Top")
		(15 "B.Paste" user "Package Geometry/Pastemask Bottom")
		(5 "F.SilkS" user "Ref Des/Silkscreen Top")
		(7 "B.SilkS" user "Ref Des/Silkscreen Bottom")
		(1 "F.Mask" user "Board Geometry/Soldermask Top")
		(3 "B.Mask" user "Board Geometry/Soldermask Bottom")
		(17 "Dwgs.User" user "User.Drawings")
		(19 "Cmts.User" user "User.Comments")
		(21 "Eco1.User" user "User.Eco1")
		(23 "Eco2.User" user "User.Eco2")
		(25 "Edge.Cuts" user "Board Geometry/Outline")
		(27 "Margin" user)
		(31 "F.CrtYd" user "Package Geometry/Place Bound Top")
		(29 "B.CrtYd" user "Package Geometry/Place Bound Bottom")
		(35 "F.Fab" user "Ref Des/Assembly Top")
		(33 "B.Fab" user "Ref Des/Assembly Bottom")
	)
	(footprint ""
		(layer "F.Cu")
		(at 389.409178 -182.743856 180)
		(property "Reference" "PU47"
			(at 4.140454 -6.180582 0)
			(unlocked yes)
			(layer "F.SilkS")
			(effects
				(font
					(size 0.7874 0.5842)
					(thickness 0.1524)
				)
				(justify left)
			)
		)
		(property "Value" ""
			(at 0 0 180)
			(layer "F.Fab")
			(effects
				(font
					(size 1.27 1.27)
				)
			)
		)
		(duplicate_pad_numbers_are_jumpers no)
		(fp_line
			(start 2.500122 2.999994)
			(end 2.2987 2.999994)
			(stroke
				(width 0.1524)
				(type default)
			)
			(layer "F.SilkS")
		)
		(fp_line
			(start 2.500122 2.339594)
			(end 2.500122 2.999994)
			(stroke
				(width 0.1524)
				(type default)
			)
			(layer "F.SilkS")
		)
		(fp_line
			(start 2.500122 -2.999994)
			(end 2.500122 -2.44348)
			(stroke
				(width 0.1524)
				(type default)
			)
			(layer "F.SilkS")
		)
		(fp_line
			(start 2.31394 -2.999994)
			(end 2.500122 -2.999994)
			(stroke
				(width 0.1524)
				(type default)
			)
			(layer "F.SilkS")
		)
		(fp_line
			(start -2.2987 2.999994)
			(end -2.500122 2.999994)
			(stroke
				(width 0.1524)
				(type default)
			)
			(layer "F.SilkS")
		)
		(fp_line
			(start -2.500122 2.999994)
			(end -2.500122 2.339594)
			(stroke
				(width 0.1524)
				(type default)
			)
			(layer "F.SilkS")
		)
		(fp_line
			(start -2.500122 0.6604)
			(end -2.500122 0.229108)
			(stroke
				(width 0.1524)
				(type default)
			)
			(layer "F.SilkS")
		)
		(fp_line
			(start -2.500122 -2.529078)
			(end -2.500122 -2.999994)
			(stroke
				(width 0.1524)
				(type default)
			)
			(layer "F.SilkS")
		)
		(fp_line
			(start -2.500122 -2.999994)
			(end -2.24409 -2.999994)
			(stroke
				(width 0.1524)
				(type default)
			)
			(layer "F.SilkS")
		)
		(fp_poly
			(pts
				(xy -2.700274 -2.537206) (xy -3.385312 -2.765806) (xy -2.928874 -3.222244)
			)
			(stroke
				(width 0)
				(type default)
			)
			(fill yes)
			(layer "F.SilkS")
		)
		(fp_line
			(start 2.500122 2.999994)
			(end -2.500122 2.999994)
			(stroke
				(width 0.1)
				(type default)
			)
			(layer "F.Fab")
		)
		(fp_line
			(start 2.500122 -2.999994)
			(end 2.500122 2.999994)
			(stroke
				(width 0.1)
				(type default)
			)
			(layer "F.Fab")
		)
		(fp_line
			(start -2.500122 2.999994)
			(end -2.500122 -2.999994)
			(stroke
				(width 0.1)
				(type default)
			)
			(layer "F.Fab")
		)
		(fp_line
			(start -2.500122 -2.999994)
			(end 2.500122 -2.999994)
			(stroke
				(width 0.1)
				(type default)
			)
			(layer "F.Fab")
		)
		(fp_poly
			(pts
				(xy -4.218432 -2.783078) (xy -4.218432 -1.767078) (xy -3.202432 -2.275078)
			)
			(stroke
				(width 0)
				(type default)
			)
			(fill yes)
			(layer "F.Fab")
		)
		(pad "1" smd rect
			(at -2.400046 -2.275078 270)
			(size 0.2286 0.6096)
			(layers "F.Cu" "F.Mask" "F.Paste")
			(net "PVDDCR_CPU0_P0_VOS4")
		)
		(pad "2" smd rect
			(at -2.400046 -1.82499 270)
			(size 0.2286 0.6096)
			(layers "F.Cu" "F.Mask" "F.Paste")
			(net "GND")
		)
		(pad "3" smd rect
			(at -2.400046 -1.374902 270)
			(size 0.2286 0.6096)
			(layers "F.Cu" "F.Mask" "F.Paste")
			(net "PVDDCR_CPU0_P0_VCC4")
		)
		(pad "4" smd rect
			(at -2.400046 -0.925068 270)
			(size 0.2286 0.6096)
			(layers "F.Cu" "F.Mask" "F.Paste")
			(net "PVDDCR_CPU0_P0_PVCC")
		)
		(pad "5" smd rect
			(at -2.400046 -0.47498 270)
			(size 0.2286 0.6096)
			(layers "F.Cu" "F.Mask" "F.Paste")
			(net "GND")
		)
		(pad "6" smd rect
			(at -2.400046 -0.024892 270)
			(size 0.2286 0.6096)
			(layers "F.Cu" "F.Mask" "F.Paste")
			(net "NC_PVDDCR_CPU0_P0_GL1_4")
		)
		(pad "7_9-20_24" smd circle
			(at 0 1.150112 270)
			(size 0 0)
			(layers "F.Cu" "F.Mask" "F.Paste")
			(net "GND")
		)
		(pad "10_19" smd rect
			(at 0 2.899918 270)
			(size 0.6096 4.318)
			(layers "F.Cu" "F.Mask" "F.Paste")
			(net "SW_PVDDCR_CPU0_P0_SW4")
		)
		(pad "25_29" smd rect
			(at 1.549908 -1.279906 90)
			(size 2.0574 2.3114)
			(layers "F.Cu" "F.Mask" "F.Paste")
			(net "SW_P12V_AUX_PVDDCR_CPU0_P0_FLT")
		)
		(pad "30" smd rect
			(at 2.05994 -2.899918 180)
			(size 0.2286 0.6096)
			(layers "F.Cu" "F.Mask" "F.Paste")
			(net "SW_P12V_AUX_PVDDCR_CPU0_P0_FLT")
		)
		(pad "31" smd rect
			(at 1.610106 -2.899918 180)
			(size 0.2286 0.6096)
			(layers "F.Cu" "F.Mask" "F.Paste")
			(net "NC_PVDDCR_CPU0_P0_DNC4")
		)
		(pad "32" smd rect
			(at 1.160018 -2.899918 180)
			(size 0.2286 0.6096)
			(layers "F.Cu" "F.Mask" "F.Paste")
			(net "SW_PVDDCR_CPU0_P0_PH4")
		)
		(pad "33" smd rect
			(at 0.70993 -2.899918 180)
			(size 0.2286 0.6096)
			(layers "F.Cu" "F.Mask" "F.Paste")
			(net "SW_PVDDCR_CPU0_P0_BOOT4")
		)
		(pad "34" smd rect
			(at 0.260096 -2.899918 180)
			(size 0.2286 0.6096)
			(layers "F.Cu" "F.Mask" "F.Paste")
			(net "PVDDCR_CPU0_P0_PWM4")
		)
		(pad "35" smd rect
			(at -0.189992 -2.899918 180)
			(size 0.2286 0.6096)
			(layers "F.Cu" "F.Mask" "F.Paste")
			(net "PVDDCR_CPU0_P0_VCC4")
		)
		(pad "36" smd rect
			(at -0.64008 -2.899918 180)
			(size 0.2286 0.6096)
			(layers "F.Cu" "F.Mask" "F.Paste")
			(net "PVDDCR_CPU0_P0_TEMP0")
		)
		(pad "37" smd rect
			(at -1.089914 -2.899918 180)
			(size 0.2286 0.6096)
			(layers "F.Cu" "F.Mask" "F.Paste")
			(net "PVDDCR_CPU0_P0_LSET4")
		)
		(pad "38" smd rect
			(at -1.540002 -2.899918 180)
			(size 0.2286 0.6096)
			(layers "F.Cu" "F.Mask" "F.Paste")
			(net "PVDDCR_CPU0_P0_IMON4")
		)
		(pad "39" smd rect
			(at -1.99009 -2.899918 180)
			(size 0.2286 0.6096)
			(layers "F.Cu" "F.Mask" "F.Paste")
			(net "PVDDCR_CPU0_P0_VCCS")
		)
		(pad "40" smd rect
			(at -0.87503 -1.27508 180)
			(size 1.7526 1.9558)
			(layers "F.Cu" "F.Mask" "F.Paste")
			(net "GND")
		)
		(pad "41" smd rect
			(at -1.525016 0.249936 90)
			(size 0.3048 0.4572)
			(layers "F.Cu" "F.Mask" "F.Paste")
			(net "NC_PVDDCR_CPU0_P0_GL2_4")
		)
		(zone
			(layer "F.Cu")
			(hatch none 0.5)
			(connect_pads
				(clearance 0)
			)
			(min_thickness 0.25)
			(keepout
				(tracks not_allowed)
				(vias allowed)
				(pads allowed)
				(copperpour not_allowed)
				(footprints allowed)
			)
			(placement
				(enabled no)
				(sheetname "")
			)
			(fill
				(thermal_gap 0.5)
				(thermal_bridge_width 0.5)
				(island_removal_mode 0)
			)
			(polygon
				(pts
					(xy 391.9093 -185.321702) (xy 391.9093 -184.99455) (xy 386.909056 -184.99455) (xy 386.909056 -185.322972)
					(xy 387.199378 -185.322972) (xy 387.199378 -185.288174) (xy 391.618978 -185.288174) (xy 391.618978 -185.321702)
				)
			)
		)
		(zone
			(layer "F.Cu")
			(hatch none 0.5)
			(connect_pads
				(clearance 0)
			)
			(min_thickness 0.25)
			(keepout
				(tracks not_allowed)
				(vias allowed)
				(pads allowed)
				(copperpour not_allowed)
				(footprints allowed)
			)
			(placement
				(enabled no)
				(sheetname "")
			)
			(fill
				(thermal_gap 0.5)
				(thermal_bridge_width 0.5)
				(island_removal_mode 0)
			)
			(polygon
				(pts
					(xy 389.357108 -182.497476) (xy 389.357108 -180.440076) (xy 391.211308 -180.440076) (xy 391.211308 -180.681122)
					(xy 391.453624 -180.681122) (xy 391.453624 -180.199538) (xy 387.624066 -180.199538) (xy 387.624066 -180.38445)
					(xy 389.06577 -180.38445) (xy 389.06577 -182.54345) (xy 386.909056 -182.54345) (xy 386.909056 -182.793132)
					(xy 389.061452 -182.793132)
				)
			)
		)
	)
	(footprint ""
		(layer "F.Cu")
		(at 197.273926 -106.543856)
		(property "Reference" "C5002"
			(at 0 0 0)
			(layer "F.SilkS")
			(hide yes)
			(effects
				(font
					(size 1.27 1.27)
				)
			)
		)
		(property "Value" ""
			(at 0 0 0)
			(layer "F.Fab")
			(effects
				(font
					(size 1.27 1.27)
				)
			)
		)
		(duplicate_pad_numbers_are_jumpers no)
		(fp_line
			(start -0.7874 -0.4064)
			(end 0.7874 -0.4064)
			(stroke
				(width 0.1524)
				(type default)
			)
			(layer "F.SilkS")
		)
		(fp_line
			(start -0.7874 0.4064)
			(end -0.7874 -0.4064)
			(stroke
				(width 0.1524)
				(type default)
			)
			(layer "F.SilkS")
		)
		(fp_line
			(start 0.7874 -0.4064)
			(end 0.7874 0.4064)
			(stroke
				(width 0.1524)
				(type default)
			)
			(layer "F.SilkS")
		)
		(fp_line
			(start 0.7874 0.4064)
			(end -0.7874 0.4064)
			(stroke
				(width 0.1524)
				(type default)
			)
			(layer "F.SilkS")
		)
		(fp_line
			(start -0.67945 -0.305054)
			(end -0.12065 -0.305054)
			(stroke
				(width 0.1)
				(type default)
			)
			(layer "F.Fab")
		)
		(fp_line
			(start -0.67945 0.3048)
			(end -0.67945 -0.305054)
			(stroke
				(width 0.1)
				(type default)
			)
			(layer "F.Fab")
		)
		(fp_line
			(start -0.12065 -0.305054)
			(end -0.12065 -0.2794)
			(stroke
				(width 0.1)
				(type default)
			)
			(layer "F.Fab")
		)
		(fp_line
			(start -0.12065 -0.2794)
			(end 0.12065 -0.2794)
			(stroke
				(width 0.1)
				(type default)
			)
			(layer "F.Fab")
		)
		(fp_line
			(start -0.12065 0.2794)
			(end -0.12065 0.3048)
			(stroke
				(width 0.1)
				(type default)
			)
			(layer "F.Fab")
		)
		(fp_line
			(start -0.12065 0.3048)
			(end -0.67945 0.3048)
			(stroke
				(width 0.1)
				(type default)
			)
			(layer "F.Fab")
		)
		(fp_line
			(start 0.120396 0.2794)
			(end -0.12065 0.2794)
			(stroke
				(width 0.1)
				(type default)
			)
			(layer "F.Fab")
		)
		(fp_line
			(start 0.120396 0.3048)
			(end 0.120396 0.2794)
			(stroke
				(width 0.1)
				(type default)
			)
			(layer "F.Fab")
		)
		(fp_line
			(start 0.12065 -0.3048)
			(end 0.67945 -0.3048)
			(stroke
				(width 0.1)
				(type default)
			)
			(layer "F.Fab")
		)
		(fp_line
			(start 0.12065 -0.2794)
			(end 0.12065 -0.3048)
			(stroke
				(width 0.1)
				(type default)
			)
			(layer "F.Fab")
		)
		(fp_line
			(start 0.67945 -0.3048)
			(end 0.67945 0.3048)
			(stroke
				(width 0.1)
				(type default)
			)
			(layer "F.Fab")
		)
		(fp_line
			(start 0.67945 0.3048)
			(end 0.120396 0.3048)
			(stroke
				(width 0.1)
				(type default)
			)
			(layer "F.Fab")
		)
		(pad "1" smd circle
			(at -0.40005 0)
			(size 0 0)
			(layers "F.Cu" "F.Mask" "F.Paste")
			(net "FM_PWRGD_PVDD33_S5")
		)
		(pad "2" smd circle
			(at 0.40005 0)
			(size 0 0)
			(layers "F.Cu" "F.Mask" "F.Paste")
			(net "GND")
		)
	)
	(footprint ""
		(layer "F.Cu")
		(at 344.474546 -23.8887 -90)
		(property "Reference" "R936"
			(at 0 0 270)
			(layer "F.SilkS")
			(hide yes)
			(effects
				(font
					(size 1.27 1.27)
				)
			)
		)
		(property "Value" ""
			(at 0 0 270)
			(layer "F.Fab")
			(effects
				(font
					(size 1.27 1.27)
				)
			)
		)
		(duplicate_pad_numbers_are_jumpers no)
		(fp_line
			(start -0.7874 0.4064)
			(end -0.7874 -0.4064)
			(stroke
				(width 0.1524)
				(type default)
			)
			(layer "F.SilkS")
		)
		(fp_line
			(start 0.7874 0.4064)
			(end -0.7874 0.4064)
			(stroke
				(width 0.1524)
				(type default)
			)
			(layer "F.SilkS")
		)
		(fp_line
			(start -0.7874 -0.4064)
			(end 0.7874 -0.4064)
			(stroke
				(width 0.1524)
				(type default)
			)
			(layer "F.SilkS")
		)
		(fp_line
			(start 0.7874 -0.4064)
			(end 0.7874 0.4064)
			(stroke
				(width 0.1524)
				(type default)
			)
			(layer "F.SilkS")
		)
		(fp_line
			(start -0.67945 0.3048)
			(end -0.67945 -0.305054)
			(stroke
				(width 0.1)
				(type default)
			)
			(layer "F.Fab")
		)
		(fp_line
			(start -0.12065 0.3048)
			(end -0.67945 0.3048)
			(stroke
				(width 0.1)
				(type default)
			)
			(layer "F.Fab")
		)
		(fp_line
			(start 0.120396 0.3048)
			(end 0.120396 0.2794)
			(stroke
				(width 0.1)
				(type default)
			)
			(layer "F.Fab")
		)
		(fp_line
			(start 0.67945 0.3048)
			(end 0.120396 0.3048)
			(stroke
				(width 0.1)
				(type default)
			)
			(layer "F.Fab")
		)
		(fp_line
			(start -0.12065 0.2794)
			(end -0.12065 0.3048)
			(stroke
				(width 0.1)
				(type default)
			)
			(layer "F.Fab")
		)
		(fp_line
			(start 0.120396 0.2794)
			(end -0.12065 0.2794)
			(stroke
				(width 0.1)
				(type default)
			)
			(layer "F.Fab")
		)
		(fp_line
			(start -0.12065 -0.2794)
			(end 0.12065 -0.2794)
			(stroke
				(width 0.1)
				(type default)
			)
			(layer "F.Fab")
		)
		(fp_line
			(start 0.12065 -0.2794)
			(end 0.12065 -0.3048)
			(stroke
				(width 0.1)
				(type default)
			)
			(layer "F.Fab")
		)
		(fp_line
			(start 0.12065 -0.3048)
			(end 0.67945 -0.3048)
			(stroke
				(width 0.1)
				(type default)
			)
			(layer "F.Fab")
		)
		(fp_line
			(start 0.67945 -0.3048)
			(end 0.67945 0.3048)
			(stroke
				(width 0.1)
				(type default)
			)
			(layer "F.Fab")
		)
		(fp_line
			(start -0.67945 -0.305054)
			(end -0.12065 -0.305054)
			(stroke
				(width 0.1)
				(type default)
			)
			(layer "F.Fab")
		)
		(fp_line
			(start -0.12065 -0.305054)
			(end -0.12065 -0.2794)
			(stroke
				(width 0.1)
				(type default)
			)
			(layer "F.Fab")
		)
		(pad "1" smd circle
			(at -0.40005 0 270)
			(size 0 0)
			(layers "F.Cu" "F.Mask" "F.Paste")
			(net "FM_SMERR_BUF_LED_N")
		)
		(pad "2" smd circle
			(at 0.40005 0 270)
			(size 0 0)
			(layers "F.Cu" "F.Mask" "F.Paste")
			(net "FM_SMERR_BUF_R_LED_N")
		)
	)
	(footprint ""
		(layer "F.Cu")
		(at 5.164328 -131.305554 180)
		(property "Reference" "R4082"
			(at 0 0 180)
			(layer "F.SilkS")
			(hide yes)
			(effects
				(font
					(size 1.27 1.27)
				)
			)
		)
		(property "Value" ""
			(at 0 0 180)
			(layer "F.Fab")
			(effects
				(font
					(size 1.27 1.27)
				)
			)
		)
		(duplicate_pad_numbers_are_jumpers no)
		(fp_line
			(start 0.7874 0.4064)
			(end -0.7874 0.4064)
			(stroke
				(width 0.1524)
				(type default)
			)
			(layer "F.SilkS")
		)
		(fp_line
			(start 0.7874 -0.4064)
			(end 0.7874 0.4064)
			(stroke
				(width 0.1524)
				(type default)
			)
			(layer "F.SilkS")
		)
		(fp_line
			(start -0.7874 0.4064)
			(end -0.7874 -0.4064)
			(stroke
				(width 0.1524)
				(type default)
			)
			(layer "F.SilkS")
		)
		(fp_line
			(start -0.7874 -0.4064)
			(end 0.7874 -0.4064)
			(stroke
				(width 0.1524)
				(type default)
			)
			(layer "F.SilkS")
		)
		(fp_line
			(start 0.67945 0.3048)
			(end 0.120396 0.3048)
			(stroke
				(width 0.1)
				(type default)
			)
			(layer "F.Fab")
		)
		(fp_line
			(start 0.67945 -0.3048)
			(end 0.67945 0.3048)
			(stroke
				(width 0.1)
				(type default)
			)
			(layer "F.Fab")
		)
		(fp_line
			(start 0.12065 -0.2794)
			(end 0.12065 -0.3048)
			(stroke
				(width 0.1)
				(type default)
			)
			(layer "F.Fab")
		)
		(fp_line
			(start 0.12065 -0.3048)
			(end 0.67945 -0.3048)
			(stroke
				(width 0.1)
				(type default)
			)
			(layer "F.Fab")
		)
		(fp_line
			(start 0.120396 0.3048)
			(end 0.120396 0.2794)
			(stroke
				(width 0.1)
				(type default)
			)
			(layer "F.Fab")
		)
		(fp_line
			(start 0.120396 0.2794)
			(end -0.12065 0.2794)
			(stroke
				(width 0.1)
				(type default)
			)
			(layer "F.Fab")
		)
		(fp_line
			(start -0.12065 0.3048)
			(end -0.67945 0.3048)
			(stroke
				(width 0.1)
				(type default)
			)
			(layer "F.Fab")
		)
		(fp_line
			(start -0.12065 0.2794)
			(end -0.12065 0.3048)
			(stroke
				(width 0.1)
				(type default)
			)
			(layer "F.Fab")
		)
		(fp_line
			(start -0.12065 -0.2794)
			(end 0.12065 -0.2794)
			(stroke
				(width 0.1)
				(type default)
			)
			(layer "F.Fab")
		)
		(fp_line
			(start -0.12065 -0.305054)
			(end -0.12065 -0.2794)
			(stroke
				(width 0.1)
				(type default)
			)
			(layer "F.Fab")
		)
		(fp_line
			(start -0.67945 0.3048)
			(end -0.67945 -0.305054)
			(stroke
				(width 0.1)
				(type default)
			)
			(layer "F.Fab")
		)
		(fp_line
			(start -0.67945 -0.305054)
			(end -0.12065 -0.305054)
			(stroke
				(width 0.1)
				(type default)
			)
			(layer "F.Fab")
		)
		(pad "1" smd circle
			(at -0.40005 0 180)
			(size 0 0)
			(layers "F.Cu" "F.Mask" "F.Paste")
			(net "CLK_GEN2_SMB_SADR")
		)
		(pad "2" smd circle
			(at 0.40005 0 180)
			(size 0 0)
			(layers "F.Cu" "F.Mask" "F.Paste")
			(net "GND")
		)
	)
)
